# S9S_MB_2U (Grand Teton) — schematic netlist excerpt (pin names and nets, part order shuffled) for the footprints in the layout excerpt that follows; sources: Cadence DE-HDL packaged netlist, KiCad conversion of 03242023_DA0F0TMBIJ0_F0T_Motherboard_J_brd_V01_OCP.brd

C236  Q_CAP  10UF 6.3V 20% X6S  pkg C0402  page 77 : A = PVCCIN_CPU1 ; B = GND
PC319  Q_CAPP  560UF 2.5V 20% OSCON  pkg THLF  page 267 : A = PVCCIN_CPU0 ; B = GND
R1605  Q_RES  1K 1% CHIP  pkg 0402LF  page 190 : A = PD_M2_0_DEVSLP ; B = GND

(kicad_pcb
	(version 20260206)
	(generator "pcbnew")
	(generator_version "10.0")
	(general
		(thickness 1.6)
		(legacy_teardrops no)
	)
	(paper "A4")
	(title_block
		(title "03242023_DA0F0TMBIJ0_F0T_Motherboard_J_brd_V01_OCP.brd")
		(comment 1 "Grand Teton / footprints 2034-2036 of 6105")
	)
	(layers
		(0 "F.Cu" signal "TOP")
		(4 "In1.Cu" signal "GND")
		(6 "In2.Cu" signal "IN1")
		(8 "In3.Cu" signal "GND1")
		(10 "In4.Cu" signal "IN2")
		(12 "In5.Cu" signal "GND2")
		(14 "In6.Cu" signal "IN3")
		(16 "In7.Cu" signal "GND3")
		(18 "In8.Cu" signal "VCC")
		(20 "In9.Cu" signal "VCC1")
		(22 "In10.Cu" signal "GND4")
		(24 "In11.Cu" signal "IN4")
		(26 "In12.Cu" signal "GND5")
		(28 "In13.Cu" signal "IN5")
		(30 "In14.Cu" signal "GND6")
		(32 "In15.Cu" signal "IN6")
		(34 "In16.Cu" signal "GND7")
		(2 "B.Cu" signal "BOTTOM")
		(9 "F.Adhes" user "F.Adhesive")
		(11 "B.Adhes" user "B.Adhesive")
		(13 "F.Paste" user "Package Geometry/Pastemask Top")
		(15 "B.Paste" user "Package Geometry/Pastemask Bottom")
		(5 "F.SilkS" user "Ref Des/Silkscreen Top")
		(7 "B.SilkS" user "Ref Des/Silkscreen Bottom")
		(1 "F.Mask" user "Board Geometry/Soldermask Top")
		(3 "B.Mask" user "Board Geometry/Soldermask Bottom")
		(17 "Dwgs.User" user "User.Drawings")
		(19 "Cmts.User" user "User.Comments")
		(21 "Eco1.User" user "User.Eco1")
		(23 "Eco2.User" user "User.Eco2")
		(25 "Edge.Cuts" user "Board Geometry/Outline")
		(27 "Margin" user)
		(31 "F.CrtYd" user "Package Geometry/Place Bound Top")
		(29 "B.CrtYd" user "Package Geometry/Place Bound Bottom")
		(35 "F.Fab" user "Ref Des/Assembly Top")
		(33 "B.Fab" user "Ref Des/Assembly Bottom")
	)
	(footprint ""
		(layer "F.Cu")
		(at 164.52088 -46.954948 180)
		(property "Reference" "R1605"
			(at 0 0 180)
			(layer "F.SilkS")
			(hide yes)
			(effects
				(font
					(size 1.27 1.27)
				)
			)
		)
		(property "Value" ""
			(at 0 0 180)
			(layer "F.Fab")
			(effects
				(font
					(size 1.27 1.27)
				)
			)
		)
		(duplicate_pad_numbers_are_jumpers no)
		(fp_line
			(start 0.7874 0.4064)
			(end -0.7874 0.4064)
			(stroke
				(width 0.1524)
				(type default)
			)
			(layer "F.SilkS")
		)
		(fp_line
			(start 0.7874 -0.4064)
			(end 0.7874 0.4064)
			(stroke
				(width 0.1524)
				(type default)
			)
			(layer "F.SilkS")
		)
		(fp_line
			(start -0.7874 0.4064)
			(end -0.7874 -0.4064)
			(stroke
				(width 0.1524)
				(type default)
			)
			(layer "F.SilkS")
		)
		(fp_line
			(start -0.7874 -0.4064)
			(end 0.7874 -0.4064)
			(stroke
				(width 0.1524)
				(type default)
			)
			(layer "F.SilkS")
		)
		(fp_line
			(start 0.67945 0.3048)
			(end 0.120396 0.3048)
			(stroke
				(width 0.1)
				(type default)
			)
			(layer "F.Fab")
		)
		(fp_line
			(start 0.67945 -0.3048)
			(end 0.67945 0.3048)
			(stroke
				(width 0.1)
				(type default)
			)
			(layer "F.Fab")
		)
		(fp_line
			(start 0.12065 -0.2794)
			(end 0.12065 -0.3048)
			(stroke
				(width 0.1)
				(type default)
			)
			(layer "F.Fab")
		)
		(fp_line
			(start 0.12065 -0.3048)
			(end 0.67945 -0.3048)
			(stroke
				(width 0.1)
				(type default)
			)
			(layer "F.Fab")
		)
		(fp_line
			(start 0.120396 0.3048)
			(end 0.120396 0.2794)
			(stroke
				(width 0.1)
				(type default)
			)
			(layer "F.Fab")
		)
		(fp_line
			(start 0.120396 0.2794)
			(end -0.12065 0.2794)
			(stroke
				(width 0.1)
				(type default)
			)
			(layer "F.Fab")
		)
		(fp_line
			(start -0.12065 0.3048)
			(end -0.67945 0.3048)
			(stroke
				(width 0.1)
				(type default)
			)
			(layer "F.Fab")
		)
		(fp_line
			(start -0.12065 0.2794)
			(end -0.12065 0.3048)
			(stroke
				(width 0.1)
				(type default)
			)
			(layer "F.Fab")
		)
		(fp_line
			(start -0.12065 -0.2794)
			(end 0.12065 -0.2794)
			(stroke
				(width 0.1)
				(type default)
			)
			(layer "F.Fab")
		)
		(fp_line
			(start -0.12065 -0.305054)
			(end -0.12065 -0.2794)
			(stroke
				(width 0.1)
				(type default)
			)
			(layer "F.Fab")
		)
		(fp_line
			(start -0.67945 0.3048)
			(end -0.67945 -0.305054)
			(stroke
				(width 0.1)
				(type default)
			)
			(layer "F.Fab")
		)
		(fp_line
			(start -0.67945 -0.305054)
			(end -0.12065 -0.305054)
			(stroke
				(width 0.1)
				(type default)
			)
			(layer "F.Fab")
		)
		(pad "1" smd circle
			(at -0.40005 0 180)
			(size 0 0)
			(layers "F.Cu" "F.Mask" "F.Paste")
			(net "PD_M2_0_DEVSLP")
		)
		(pad "2" smd circle
			(at 0.40005 0 180)
			(size 0 0)
			(layers "F.Cu" "F.Mask" "F.Paste")
			(net "GND")
		)
	)
	(footprint ""
		(layer "F.Cu")
		(at 358.84104 -315.66739 90)
		(property "Reference" "PC319"
			(at 0 0 90)
			(layer "F.SilkS")
			(hide yes)
			(effects
				(font
					(size 1.27 1.27)
				)
			)
		)
		(property "Value" ""
			(at 0 0 90)
			(layer "F.Fab")
			(effects
				(font
					(size 1.27 1.27)
				)
			)
		)
		(duplicate_pad_numbers_are_jumpers no)
		(fp_line
			(start 2.750058 0.999998)
			(end -2.750058 0.999998)
			(stroke
				(width 0.1524)
				(type default)
			)
			(layer "F.SilkS")
		)
		(fp_circle
			(center 0 0.999998)
			(end 0 3.750056)
			(stroke
				(width 0.1524)
				(type default)
			)
			(fill no)
			(layer "F.SilkS")
		)
		(fp_poly
			(pts
				(arc
					(start 2.750058 0.999998)
					(mid 0 3.750056)
					(end -2.750058 0.999998)
				)
			)
			(stroke
				(width 0)
				(type default)
			)
			(fill yes)
			(layer "F.SilkS")
		)
		(fp_circle
			(center 0 0.999998)
			(end 0 3.750056)
			(stroke
				(width 0.1)
				(type default)
			)
			(fill no)
			(layer "F.Fab")
		)
		(pad "1" thru_hole rect
			(at 0 0 90)
			(size 1.5748 1.5748)
			(drill 1.0668)
			(layers "*.Cu" "*.Mask")
			(remove_unused_layers no)
			(net "PVCCIN_CPU0")
			(clearance 0)
			(padstack
				(mode front_inner_back)
				(layer "Inner"
					(shape circle)
					(size 1.5748 1.5748)
					(clearance 0)
				)
				(layer "B.Cu"
					(shape rect)
					(size 1.5748 1.5748)
					(clearance 0)
				)
			)
		)
		(pad "2" thru_hole circle
			(at 0 1.999996 90)
			(size 1.5748 1.5748)
			(drill 1.0668)
			(layers "*.Cu" "*.Mask")
			(remove_unused_layers no)
			(net "GND")
			(clearance 0)
		)
	)
	(footprint ""
		(layer "F.Cu")
		(at 105.3084 -249.320558 -90)
		(property "Reference" "C236"
			(at 0 0 270)
			(layer "F.SilkS")
			(hide yes)
			(effects
				(font
					(size 1.27 1.27)
				)
			)
		)
		(property "Value" ""
			(at 0 0 270)
			(layer "F.Fab")
			(effects
				(font
					(size 1.27 1.27)
				)
			)
		)
		(duplicate_pad_numbers_are_jumpers no)
		(fp_line
			(start -0.7874 0.4064)
			(end -0.7874 -0.4064)
			(stroke
				(width 0.1524)
				(type default)
			)
			(layer "F.SilkS")
		)
		(fp_line
			(start 0.7874 0.4064)
			(end -0.7874 0.4064)
			(stroke
				(width 0.1524)
				(type default)
			)
			(layer "F.SilkS")
		)
		(fp_line
			(start -0.7874 -0.4064)
			(end 0.7874 -0.4064)
			(stroke
				(width 0.1524)
				(type default)
			)
			(layer "F.SilkS")
		)
		(fp_line
			(start 0.7874 -0.4064)
			(end 0.7874 0.4064)
			(stroke
				(width 0.1524)
				(type default)
			)
			(layer "F.SilkS")
		)
		(fp_line
			(start -0.67945 0.3048)
			(end -0.67945 -0.305054)
			(stroke
				(width 0.1)
				(type default)
			)
			(layer "F.Fab")
		)
		(fp_line
			(start -0.12065 0.3048)
			(end -0.67945 0.3048)
			(stroke
				(width 0.1)
				(type default)
			)
			(layer "F.Fab")
		)
		(fp_line
			(start 0.120396 0.3048)
			(end 0.120396 0.2794)
			(stroke
				(width 0.1)
				(type default)
			)
			(layer "F.Fab")
		)
		(fp_line
			(start 0.67945 0.3048)
			(end 0.120396 0.3048)
			(stroke
				(width 0.1)
				(type default)
			)
			(layer "F.Fab")
		)
		(fp_line
			(start -0.12065 0.2794)
			(end -0.12065 0.3048)
			(stroke
				(width 0.1)
				(type default)
			)
			(layer "F.Fab")
		)
		(fp_line
			(start 0.120396 0.2794)
			(end -0.12065 0.2794)
			(stroke
				(width 0.1)
				(type default)
			)
			(layer "F.Fab")
		)
		(fp_line
			(start -0.12065 -0.2794)
			(end 0.12065 -0.2794)
			(stroke
				(width 0.1)
				(type default)
			)
			(layer "F.Fab")
		)
		(fp_line
			(start 0.12065 -0.2794)
			(end 0.12065 -0.3048)
			(stroke
				(width 0.1)
				(type default)
			)
			(layer "F.Fab")
		)
		(fp_line
			(start 0.12065 -0.3048)
			(end 0.67945 -0.3048)
			(stroke
				(width 0.1)
				(type default)
			)
			(layer "F.Fab")
		)
		(fp_line
			(start 0.67945 -0.3048)
			(end 0.67945 0.3048)
			(stroke
				(width 0.1)
				(type default)
			)
			(layer "F.Fab")
		)
		(fp_line
			(start -0.67945 -0.305054)
			(end -0.12065 -0.305054)
			(stroke
				(width 0.1)
				(type default)
			)
			(layer "F.Fab")
		)
		(fp_line
			(start -0.12065 -0.305054)
			(end -0.12065 -0.2794)
			(stroke
				(width 0.1)
				(type default)
			)
			(layer "F.Fab")
		)
		(pad "1" smd circle
			(at -0.40005 0 270)
			(size 0 0)
			(layers "F.Cu" "F.Mask" "F.Paste")
			(net "PVCCIN_CPU1")
		)
		(pad "2" smd circle
			(at 0.40005 0 270)
			(size 0 0)
			(layers "F.Cu" "F.Mask" "F.Paste")
			(net "GND")
		)
	)
)
